FILE_TYPE = MULTI_PHYS_TABLE;

PART 'AT24MAC402_SOT23_5'
CLASS = IC 

{========================================================================================}
:'CLS_PN'         |'VALUE'                = 'JEDEC_TYPE'             |'ALT_SYMBOLS'                 |'DESCRIPTION'                                                                                             | CPN_STATUS        ;
{========================================================================================}
 'A221-00001-FB'  |'AT24MAC402-STUM-T'    = 'SOT23_5_H039'           |'(SOT23_5_H039)'              |'IC,I2C,EEPROM,2KBIT WITH FACTORY-PROGRAMMED EUI-48 OR EUI-64 ADDRESS,1.7-5.5V,SOT23-5,SMT,-40C TO 85C'   |''
 'A221-00002-FB'  |'AT24MAC602-STUM-T'    = 'SOT23_5_H039'           |'(SOT23_5_H039)'              |'IC,I2C,EEPROM,2KBIT WITH FACTORY-PROGRAMMED EUI-64 ADDRESS,1.7-5.5V,SOT23-5,SMT,-40C TO 85C'             |''

END_PART

END.

